FILE_TYPE = MACRO_DRAWING;
SET COLOR_WIRE YELLOW;
SET COLOR_PROP MONO;
SET COLOR_DOT WHITE;
SET COLOR_ARC YELLOW;
SET COLOR_BODY GREEN;
SET COLOR_NOTE MONO;
SET PROP_DISPLAY VALUE;
SET PAGE_NUMBER P69;
FORCEADD SKX_EXT_B..15
(-4275 2700);
FORCEPROP 1 LAST LOCATION U2D1
J 0
(-5025 3950);
DISPLAY 0.617021 (-5025 3950);
PAINT AQUA (-5025 3950);
FORCEPROP 1 LAST PART_NUMBER TBD
J 0
(-5025 1500);
DISPLAY 0.617021 (-5025 1500);
PAINT BLUE (-5025 1500);
FORCEPROP 1 LAST MATERIAL IC
J 0
(-5025 3900);
DISPLAY 0.617021 (-5025 3900);
PAINT SKYBLUE (-5025 3900);
FORCEPROP 2 LASTPIN (-3475 3700) $PN CA12
J 0
(-3465 3710);
DISPLAY 0.617021 (-3465 3710);
PAINT ORANGE (-3465 3710);
FORCEPROP 2 LASTPIN (-3475 3650) $PN CB11
J 0
(-3465 3660);
DISPLAY 0.617021 (-3465 3660);
PAINT ORANGE (-3465 3660);
FORCEPROP 2 LASTPIN (-3475 3600) $PN CD11
J 0
(-3465 3610);
DISPLAY 0.617021 (-3465 3610);
PAINT ORANGE (-3465 3610);
FORCEPROP 2 LASTPIN (-3475 3550) $PN CF11
J 0
(-3465 3560);
DISPLAY 0.617021 (-3465 3560);
PAINT ORANGE (-3465 3560);
FORCEPROP 2 LASTPIN (-3475 3500) $PN CG12
J 0
(-3465 3510);
DISPLAY 0.617021 (-3465 3510);
PAINT ORANGE (-3465 3510);
FORCEPROP 2 LASTPIN (-3475 3450) $PN CH13
J 0
(-3465 3460);
DISPLAY 0.617021 (-3465 3460);
PAINT ORANGE (-3465 3460);
FORCEPROP 2 LASTPIN (-3475 3400) $PN CK13
J 0
(-3465 3410);
DISPLAY 0.617021 (-3465 3410);
PAINT ORANGE (-3465 3410);
FORCEPROP 2 LASTPIN (-3475 3350) $PN CR14
J 0
(-3465 3360);
DISPLAY 0.617021 (-3465 3360);
PAINT ORANGE (-3465 3360);
FORCEPROP 2 LASTPIN (-3475 3300) $PN CV13
J 0
(-3465 3310);
DISPLAY 0.617021 (-3465 3310);
PAINT ORANGE (-3465 3310);
FORCEPROP 2 LASTPIN (-3475 3250) $PN CW16
J 0
(-3465 3260);
DISPLAY 0.617021 (-3465 3260);
PAINT ORANGE (-3465 3260);
FORCEPROP 2 LASTPIN (-3475 3200) $PN DB15
J 0
(-3465 3210);
DISPLAY 0.617021 (-3465 3210);
PAINT ORANGE (-3465 3210);
FORCEPROP 2 LASTPIN (-3475 3150) $PN DD15
J 0
(-3465 3160);
DISPLAY 0.617021 (-3465 3160);
PAINT ORANGE (-3465 3160);
FORCEPROP 2 LASTPIN (-3475 3100) $PN DE16
J 0
(-3465 3110);
DISPLAY 0.617021 (-3465 3110);
PAINT ORANGE (-3465 3110);
FORCEPROP 2 LASTPIN (-3475 3050) $PN DF17
J 0
(-3465 3060);
DISPLAY 0.617021 (-3465 3060);
PAINT ORANGE (-3465 3060);
FORCEPROP 2 LASTPIN (-3475 3000) $PN DH17
J 0
(-3465 3010);
DISPLAY 0.617021 (-3465 3010);
PAINT ORANGE (-3465 3010);
FORCEPROP 2 LASTPIN (-3475 2950) $PN DJ18
J 0
(-3465 2960);
DISPLAY 0.617021 (-3465 2960);
PAINT ORANGE (-3465 2960);
FORCEPROP 2 LASTPIN (-3475 2900) $PN DJ20
J 0
(-3465 2910);
DISPLAY 0.617021 (-3465 2910);
PAINT ORANGE (-3465 2910);
FORCEPROP 2 LASTPIN (-3475 2850) $PN DK19
J 0
(-3465 2860);
DISPLAY 0.617021 (-3465 2860);
PAINT ORANGE (-3465 2860);
FORCEPROP 2 LASTPIN (-3475 2800) $PN DN20
J 0
(-3465 2810);
DISPLAY 0.617021 (-3465 2810);
PAINT ORANGE (-3465 2810);
FORCEPROP 2 LASTPIN (-3475 2750) $PN DP21
J 0
(-3465 2760);
DISPLAY 0.617021 (-3465 2760);
PAINT ORANGE (-3465 2760);
FORCEPROP 2 LASTPIN (-3475 2650) $PN CC12
J 0
(-3465 2660);
DISPLAY 0.617021 (-3465 2660);
PAINT ORANGE (-3465 2660);
FORCEPROP 2 LASTPIN (-3475 2600) $PN CC10
J 0
(-3465 2610);
DISPLAY 0.617021 (-3465 2610);
PAINT ORANGE (-3465 2610);
FORCEPROP 2 LASTPIN (-3475 2550) $PN CE12
J 0
(-3465 2560);
DISPLAY 0.617021 (-3465 2560);
PAINT ORANGE (-3465 2560);
FORCEPROP 2 LASTPIN (-3475 2500) $PN CH11
J 0
(-3465 2510);
DISPLAY 0.617021 (-3465 2510);
PAINT ORANGE (-3465 2510);
FORCEPROP 2 LASTPIN (-3475 2450) $PN CF13
J 0
(-3465 2460);
DISPLAY 0.617021 (-3465 2460);
PAINT ORANGE (-3465 2460);
FORCEPROP 2 LASTPIN (-3475 2400) $PN CJ14
J 0
(-3465 2410);
DISPLAY 0.617021 (-3465 2410);
PAINT ORANGE (-3465 2410);
FORCEPROP 2 LASTPIN (-3475 2350) $PN CM13
J 0
(-3465 2360);
DISPLAY 0.617021 (-3465 2360);
PAINT ORANGE (-3465 2360);
FORCEPROP 2 LASTPIN (-3475 2300) $PN CU14
J 0
(-3465 2310);
DISPLAY 0.617021 (-3465 2310);
PAINT ORANGE (-3465 2310);
FORCEPROP 2 LASTPIN (-3475 2250) $PN CW14
J 0
(-3465 2260);
DISPLAY 0.617021 (-3465 2260);
PAINT ORANGE (-3465 2260);
FORCEPROP 2 LASTPIN (-3475 2200) $PN DA16
J 0
(-3465 2210);
DISPLAY 0.617021 (-3465 2210);
PAINT ORANGE (-3465 2210);
FORCEPROP 2 LASTPIN (-3475 2150) $PN DC16
J 0
(-3465 2160);
DISPLAY 0.617021 (-3465 2160);
PAINT ORANGE (-3465 2160);
FORCEPROP 2 LASTPIN (-3475 2100) $PN DF15
J 0
(-3465 2110);
DISPLAY 0.617021 (-3465 2110);
PAINT ORANGE (-3465 2110);
FORCEPROP 2 LASTPIN (-3475 2050) $PN DD17
J 0
(-3465 2060);
DISPLAY 0.617021 (-3465 2060);
PAINT ORANGE (-3465 2060);
FORCEPROP 2 LASTPIN (-3475 2000) $PN DG18
J 0
(-3465 2010);
DISPLAY 0.617021 (-3465 2010);
PAINT ORANGE (-3465 2010);
FORCEPROP 2 LASTPIN (-3475 1950) $PN DK17
J 0
(-3465 1960);
DISPLAY 0.617021 (-3465 1960);
PAINT ORANGE (-3465 1960);
FORCEPROP 2 LASTPIN (-3475 1900) $PN DH19
J 0
(-3465 1910);
DISPLAY 0.617021 (-3465 1910);
PAINT ORANGE (-3465 1910);
FORCEPROP 2 LASTPIN (-3475 1850) $PN DG20
J 0
(-3465 1860);
DISPLAY 0.617021 (-3465 1860);
PAINT ORANGE (-3465 1860);
FORCEPROP 2 LASTPIN (-3475 1800) $PN DL20
J 0
(-3465 1810);
DISPLAY 0.617021 (-3465 1810);
PAINT ORANGE (-3465 1810);
FORCEPROP 2 LASTPIN (-3475 1750) $PN DM21
J 0
(-3465 1760);
DISPLAY 0.617021 (-3465 1760);
PAINT ORANGE (-3465 1760);
FORCEPROP 2 LASTPIN (-3475 1700) $PN DT21
J 0
(-3465 1710);
DISPLAY 0.617021 (-3465 1710);
PAINT ORANGE (-3465 1710);
FORCEPROP 2 LASTPIN (-5075 3700) $PN CA16
J 2
(-5085 3710);
DISPLAY 0.617021 (-5085 3710);
PAINT ORANGE (-5085 3710);
FORCEPROP 2 LASTPIN (-5075 3650) $PN BY15
J 2
(-5085 3660);
DISPLAY 0.617021 (-5085 3660);
PAINT ORANGE (-5085 3660);
FORCEPROP 2 LASTPIN (-5075 3600) $PN CD17
J 2
(-5085 3610);
DISPLAY 0.617021 (-5085 3610);
PAINT ORANGE (-5085 3610);
FORCEPROP 2 LASTPIN (-5075 3550) $PN CC14
J 2
(-5085 3560);
DISPLAY 0.617021 (-5085 3560);
PAINT ORANGE (-5085 3560);
FORCEPROP 2 LASTPIN (-5075 3500) $PN CF15
J 2
(-5085 3510);
DISPLAY 0.617021 (-5085 3510);
PAINT ORANGE (-5085 3510);
FORCEPROP 2 LASTPIN (-5075 3450) $PN CG16
J 2
(-5085 3460);
DISPLAY 0.617021 (-5085 3460);
PAINT ORANGE (-5085 3460);
FORCEPROP 2 LASTPIN (-5075 3400) $PN CK17
J 2
(-5085 3410);
DISPLAY 0.617021 (-5085 3410);
PAINT ORANGE (-5085 3410);
FORCEPROP 2 LASTPIN (-5075 3350) $PN CJ16
J 2
(-5085 3360);
DISPLAY 0.617021 (-5085 3360);
PAINT ORANGE (-5085 3360);
FORCEPROP 2 LASTPIN (-5075 3300) $PN CM21
J 2
(-5085 3310);
DISPLAY 0.617021 (-5085 3310);
PAINT ORANGE (-5085 3310);
FORCEPROP 2 LASTPIN (-5075 3250) $PN CP19
J 2
(-5085 3260);
DISPLAY 0.617021 (-5085 3260);
PAINT ORANGE (-5085 3260);
FORCEPROP 2 LASTPIN (-5075 3200) $PN CN18
J 2
(-5085 3210);
DISPLAY 0.617021 (-5085 3210);
PAINT ORANGE (-5085 3210);
FORCEPROP 2 LASTPIN (-5075 3150) $PN CR20
J 2
(-5085 3160);
DISPLAY 0.617021 (-5085 3160);
PAINT ORANGE (-5085 3160);
FORCEPROP 2 LASTPIN (-5075 3100) $PN CW18
J 2
(-5085 3110);
DISPLAY 0.617021 (-5085 3110);
PAINT ORANGE (-5085 3110);
FORCEPROP 2 LASTPIN (-5075 3050) $PN CU20
J 2
(-5085 3060);
DISPLAY 0.617021 (-5085 3060);
PAINT ORANGE (-5085 3060);
FORCEPROP 2 LASTPIN (-5075 3000) $PN CY19
J 2
(-5085 3010);
DISPLAY 0.617021 (-5085 3010);
PAINT ORANGE (-5085 3010);
FORCEPROP 2 LASTPIN (-5075 2950) $PN DB19
J 2
(-5085 2960);
DISPLAY 0.617021 (-5085 2960);
PAINT ORANGE (-5085 2960);
FORCEPROP 2 LASTPIN (-5075 2900) $PN DC20
J 2
(-5085 2910);
DISPLAY 0.617021 (-5085 2910);
PAINT ORANGE (-5085 2910);
FORCEPROP 2 LASTPIN (-5075 2850) $PN DA22
J 2
(-5085 2860);
DISPLAY 0.617021 (-5085 2860);
PAINT ORANGE (-5085 2860);
FORCEPROP 2 LASTPIN (-5075 2800) $PN DD21
J 2
(-5085 2810);
DISPLAY 0.617021 (-5085 2810);
PAINT ORANGE (-5085 2810);
FORCEPROP 2 LASTPIN (-5075 2750) $PN DG22
J 2
(-5085 2760);
DISPLAY 0.617021 (-5085 2760);
PAINT ORANGE (-5085 2760);
FORCEPROP 2 LASTPIN (-5075 2650) $PN BY17
J 2
(-5085 2660);
DISPLAY 0.617021 (-5085 2660);
PAINT ORANGE (-5085 2660);
FORCEPROP 2 LASTPIN (-5075 2600) $PN CB15
J 2
(-5085 2610);
DISPLAY 0.617021 (-5085 2610);
PAINT ORANGE (-5085 2610);
FORCEPROP 2 LASTPIN (-5075 2550) $PN CF17
J 2
(-5085 2560);
DISPLAY 0.617021 (-5085 2560);
PAINT ORANGE (-5085 2560);
FORCEPROP 2 LASTPIN (-5075 2500) $PN CD15
J 2
(-5085 2510);
DISPLAY 0.617021 (-5085 2510);
PAINT ORANGE (-5085 2510);
FORCEPROP 2 LASTPIN (-5075 2450) $PN CE16
J 2
(-5085 2460);
DISPLAY 0.617021 (-5085 2460);
PAINT ORANGE (-5085 2460);
FORCEPROP 2 LASTPIN (-5075 2400) $PN CH17
J 2
(-5085 2410);
DISPLAY 0.617021 (-5085 2410);
PAINT ORANGE (-5085 2410);
FORCEPROP 2 LASTPIN (-5075 2350) $PN CJ18
J 2
(-5085 2360);
DISPLAY 0.617021 (-5085 2360);
PAINT ORANGE (-5085 2360);
FORCEPROP 2 LASTPIN (-5075 2300) $PN CL16
J 2
(-5085 2310);
DISPLAY 0.617021 (-5085 2310);
PAINT ORANGE (-5085 2310);
FORCEPROP 2 LASTPIN (-5075 2250) $PN CP21
J 2
(-5085 2260);
DISPLAY 0.617021 (-5085 2260);
PAINT ORANGE (-5085 2260);
FORCEPROP 2 LASTPIN (-5075 2200) $PN CN20
J 2
(-5085 2210);
DISPLAY 0.617021 (-5085 2210);
PAINT ORANGE (-5085 2210);
FORCEPROP 2 LASTPIN (-5075 2150) $PN CR18
J 2
(-5085 2160);
DISPLAY 0.617021 (-5085 2160);
PAINT ORANGE (-5085 2160);
FORCEPROP 2 LASTPIN (-5075 2100) $PN CT21
J 2
(-5085 2110);
DISPLAY 0.617021 (-5085 2110);
PAINT ORANGE (-5085 2110);
FORCEPROP 2 LASTPIN (-5075 2050) $PN CV19
J 2
(-5085 2060);
DISPLAY 0.617021 (-5085 2060);
PAINT ORANGE (-5085 2060);
FORCEPROP 2 LASTPIN (-5075 2000) $PN CW20
J 2
(-5085 2010);
DISPLAY 0.617021 (-5085 2010);
PAINT ORANGE (-5085 2010);
FORCEPROP 2 LASTPIN (-5075 1950) $PN DA20
J 2
(-5085 1960);
DISPLAY 0.617021 (-5085 1960);
PAINT ORANGE (-5085 1960);
FORCEPROP 2 LASTPIN (-5075 1900) $PN DD19
J 2
(-5085 1910);
DISPLAY 0.617021 (-5085 1910);
PAINT ORANGE (-5085 1910);
FORCEPROP 2 LASTPIN (-5075 1850) $PN DB21
J 2
(-5085 1860);
DISPLAY 0.617021 (-5085 1860);
PAINT ORANGE (-5085 1860);
FORCEPROP 2 LASTPIN (-5075 1800) $PN DC22
J 2
(-5085 1810);
DISPLAY 0.617021 (-5085 1810);
PAINT ORANGE (-5085 1810);
FORCEPROP 2 LASTPIN (-5075 1750) $PN DE22
J 2
(-5085 1760);
DISPLAY 0.617021 (-5085 1760);
PAINT ORANGE (-5085 1760);
FORCEPROP 2 LASTPIN (-5075 1700) $PN DF23
J 2
(-5085 1710);
DISPLAY 0.617021 (-5085 1710);
PAINT ORANGE (-5085 1710);
FORCEPROP 1 LAST PACK_TYPE BGA1
J 0
(-5025 4000);
PAINT SKYBLUE (-5025 4000);
DISPLAY INVISIBLE (-5025 4000);
FORCEPROP 2 LAST SEC_TYPE BGA1
J 0
(-5025 4000);
DISPLAY 1.021277 (-5025 4000);
PAINT ORANGE (-5025 4000);
DISPLAY INVISIBLE (-5025 4000);
FORCEPROP 2 LAST CDS_LIB chpset_lib
J 0
(-4275 2700);
PAINT ORANGE (-4275 2700);
DISPLAY INVISIBLE (-4275 2700);
FORCEPROP 2 LAST SEC 15
J 0
(-5025 4000);
DISPLAY 0.680851 (-5025 4000);
PAINT MONO (-5025 4000);
DISPLAY INVISIBLE (-5025 4000);
FORCEPROP 2 LAST CDS_LOCATION U2D1
J 0
(-5025 3950);
DISPLAY 0.617021 (-5025 3950);
PAINT AQUA (-5025 3950);
DISPLAY INVISIBLE (-5025 3950);
FORCEPROP 1 LAST PATH I1
J 0
(-4275 3900);
PAINT GREEN (-4275 3900);
DISPLAY INVISIBLE (-4275 3900);
FORCEADD GND..1
(-6025 1475);
FORCEPROP 3 LASTPIN (-6025 1525) SIG_NAME GND\g
J 0
(-6015 1535);
DISPLAY 0.659574 (-6015 1535);
PAINT MONO (-6015 1535);
DISPLAY INVISIBLE (-6015 1535);
FORCEPROP 1 LAST VOLTAGE 0.0V
J 0
(-6070 1432);
DISPLAY 0.340426 (-6070 1432);
PAINT SKYBLUE (-6070 1432);
DISPLAY INVISIBLE (-6070 1432);
FORCEPROP 1 LAST SIZE 1B
J 0
(-5950 1425);
DISPLAY 1.170213 (-5950 1425);
PAINT AQUA (-5950 1425);
DISPLAY INVISIBLE (-5950 1425);
FORCEPROP 2 LAST CDS_LIB mstr_symbols
J 0
(-6025 1475);
PAINT MONO (-6025 1475);
DISPLAY INVISIBLE (-6025 1475);
FORCEPROP 1 LAST BODY_TYPE PLUMBING
J 0
(-6070 1432);
DISPLAY 0.340426 (-6070 1432);
PAINT GREEN (-6070 1432);
DISPLAY INVISIBLE (-6070 1432);
FORCEPROP 1 LAST PATH I2
J 0
(-5950 1475);
DISPLAY 0.872340 (-5950 1475);
PAINT AQUA (-5950 1475);
DISPLAY INVISIBLE (-5950 1475);
FORCEPROP 1 LAST HDL_POWER GND
J 0
(-6025 1625);
DISPLAY 1.170213 (-6025 1625);
PAINT GREEN (-6025 1625);
DISPLAY INVISIBLE (-6025 1625);
FORCEADD DESIGN_NOTE..1
(-4825 1400);
FORCEPROP 0 LAST L1 CPU SYMBOLS 1-30 ARE PRELIMINARY AND SUBJECT TO CHANGE
J 0
(-5025 1275);
DISPLAY 1.021277 (-5025 1275);
PAINT ORANGE (-5025 1275);
FORCEPROP 2 LAST CDS_LIB mstr_symbols
J 0
(-4825 1400);
PAINT ORANGE (-4825 1400);
DISPLAY INVISIBLE (-4825 1400);
FORCEPROP 1 LAST COMMENT_BODY TRUE
J 0
(-4800 1500);
DISPLAY 0.978723 (-4800 1500);
PAINT ORANGE (-4800 1500);
DISPLAY INVISIBLE (-4800 1500);
FORCEADD PRELIM..10
(-4265 2690);
PAINT GRAY (-4265 2690);
FORCEPROP 2 LAST CDS_LIB mstr_misc
J 0
(-4265 2690);
PAINT ORANGE (-4265 2690);
DISPLAY INVISIBLE (-4265 2690);
FORCEPROP 1 LAST COMMENT_BODY TRUE
J 0
(-4265 2690);
PAINT ORANGE (-4265 2690);
DISPLAY INVISIBLE (-4265 2690);
FORCEADD INTEL_CORP_BPAGE..1
(0 0);
FORCEPROP 1 LAST CDS_CON_LAST_MODIFIED Tue Dec 01 11:51:38 2015
J 0
(-1425 325);
DISPLAY 1.340426 (-1425 325);
PAINT GREEN (-1425 325);
DISPLAY INVISIBLE (-1425 325);
FORCEPROP 1 LAST CUSTOM_TXT_CDS <CURRENT_DESIGN_SHEET> OF <TOTAL_DESIGN_SHEETS>
J 0
(-500 25);
PAINT GREEN (-500 25);
FORCEPROP 1 LAST CUSTOM_TXT_CDS <CON_LAST_MODIFIED>
J 0
(-1925 350);
PAINT GREEN (-1925 350);
FORCEPROP 2 LAST CUSTOM_TXT_CDS <XR_PAGE_TITLE>
J 0
(-7890 5250);
DISPLAY 0.638298 (-7890 5250);
PAINT PINK (-7890 5250);
DISPLAY INVISIBLE (-7890 5250);
FORCEPROP 1 LAST SCH_ADDRESS3 Santa Clara, CA 95052-8119
J 0
(-3975 25);
DISPLAY 0.617021 (-3975 25);
PAINT GREEN (-3975 25);
FORCEPROP 1 LAST SCH_ADDRESS2 P.O. BOX 58119
J 0
(-3975 75);
DISPLAY 0.617021 (-3975 75);
PAINT GREEN (-3975 75);
FORCEPROP 1 LAST SCH_ADDRESS1 2200 Mission College Blvd.
J 0
(-3975 125);
DISPLAY 0.617021 (-3975 125);
PAINT GREEN (-3975 125);
FORCEPROP 1 LAST SCH_TITLE SKYLAKE - SKT1 - 15 OF 21
J 0
(-7950 50);
DISPLAY 1.212766 (-7950 50);
PAINT GREEN (-7950 50);
FORCEPROP 1 LAST SCH_NUMBER H4694802
J 0
(-1300 150);
DISPLAY 1.212766 (-1300 150);
PAINT YELLOW (-1300 150);
FORCEPROP 1 LAST SCH_DEPT BESD
J 1
(-4450 100);
DISPLAY 1.212766 (-4450 100);
PAINT YELLOW (-4450 100);
FORCEPROP 1 LAST SCH_REV 2.420
J 0
(-250 150);
DISPLAY 0.978723 (-250 150);
PAINT YELLOW (-250 150);
FORCEPROP 2 LAST CDS_LIB mstr_symbols
J 0
(0 0);
PAINT ORANGE (0 0);
DISPLAY INVISIBLE (0 0);
FORCEPROP 2 LAST PAGE_BORDER TRUE
J 0
(-7890 5250);
DISPLAY 0.851064 (-7890 5250);
PAINT PINK (-7890 5250);
DISPLAY INVISIBLE (-7890 5250);
FORCEPROP 1 LAST COMMENT_BODY TRUE
J 0
(12 12);
DISPLAY 0.638298 (12 12);
PAINT GREEN (12 12);
DISPLAY INVISIBLE (12 12);
FORCEPROP 2 LAST CDS_XR_PAGE_TITLE CR-69 : @BASEBOARD_FAB2_LIB.BASEBOARD_FAB2(SCH_1):PAGE69
J 0
(-7890 5250);
DISPLAY 0.638298 (-7890 5250);
PAINT PINK (-7890 5250);
DISPLAY INVISIBLE (-7890 5250);
WIRE 16 -1 (-5075 3700)(-6025 3700);
WIRE 16 -1 (-6025 3700)(-6025 3650);
WIRE 16 -1 (-5075 3650)(-6025 3650);
WIRE 16 -1 (-6025 3650)(-6025 3600);
WIRE 16 -1 (-5075 3600)(-6025 3600);
WIRE 16 -1 (-6025 3600)(-6025 3550);
WIRE 16 -1 (-5075 3550)(-6025 3550);
WIRE 16 -1 (-6025 3550)(-6025 3500);
WIRE 16 -1 (-5075 3500)(-6025 3500);
WIRE 16 -1 (-6025 3500)(-6025 3450);
WIRE 16 -1 (-5075 3450)(-6025 3450);
WIRE 16 -1 (-6025 3450)(-6025 3400);
WIRE 16 -1 (-5075 3400)(-6025 3400);
WIRE 16 -1 (-6025 3400)(-6025 3350);
WIRE 16 -1 (-5075 3350)(-6025 3350);
WIRE 16 -1 (-6025 3350)(-6025 3300);
WIRE 16 -1 (-5075 3300)(-6025 3300);
WIRE 16 -1 (-6025 3300)(-6025 3250);
WIRE 16 -1 (-5075 3250)(-6025 3250);
WIRE 16 -1 (-6025 3250)(-6025 3200);
WIRE 16 -1 (-5075 3200)(-6025 3200);
WIRE 16 -1 (-6025 3200)(-6025 3150);
WIRE 16 -1 (-5075 3150)(-6025 3150);
WIRE 16 -1 (-6025 3150)(-6025 3100);
WIRE 16 -1 (-5075 3100)(-6025 3100);
WIRE 16 -1 (-6025 3100)(-6025 3050);
WIRE 16 -1 (-5075 3050)(-6025 3050);
WIRE 16 -1 (-6025 3050)(-6025 3000);
WIRE 16 -1 (-5075 3000)(-6025 3000);
WIRE 16 -1 (-6025 3000)(-6025 2950);
WIRE 16 -1 (-5075 2950)(-6025 2950);
WIRE 16 -1 (-6025 2950)(-6025 2900);
WIRE 16 -1 (-5075 2900)(-6025 2900);
WIRE 16 -1 (-6025 2900)(-6025 2850);
WIRE 16 -1 (-5075 2850)(-6025 2850);
WIRE 16 -1 (-6025 2850)(-6025 2800);
WIRE 16 -1 (-5075 2800)(-6025 2800);
WIRE 16 -1 (-6025 2800)(-6025 2750);
WIRE 16 -1 (-5075 2750)(-6025 2750);
WIRE 16 -1 (-6025 2750)(-6025 2650);
WIRE 16 -1 (-5075 2650)(-6025 2650);
WIRE 16 -1 (-6025 2650)(-6025 2600);
WIRE 16 -1 (-5075 2600)(-6025 2600);
WIRE 16 -1 (-6025 2600)(-6025 2550);
WIRE 16 -1 (-5075 2550)(-6025 2550);
WIRE 16 -1 (-6025 2550)(-6025 2500);
WIRE 16 -1 (-5075 2500)(-6025 2500);
WIRE 16 -1 (-6025 2500)(-6025 2450);
WIRE 16 -1 (-5075 2450)(-6025 2450);
WIRE 16 -1 (-6025 2450)(-6025 2400);
WIRE 16 -1 (-5075 2400)(-6025 2400);
WIRE 16 -1 (-6025 2400)(-6025 2350);
WIRE 16 -1 (-5075 2350)(-6025 2350);
WIRE 16 -1 (-6025 2350)(-6025 2300);
WIRE 16 -1 (-5075 2300)(-6025 2300);
WIRE 16 -1 (-6025 2300)(-6025 2250);
WIRE 16 -1 (-5075 2250)(-6025 2250);
WIRE 16 -1 (-6025 2250)(-6025 2200);
WIRE 16 -1 (-5075 2200)(-6025 2200);
WIRE 16 -1 (-6025 2200)(-6025 2150);
WIRE 16 -1 (-5075 2150)(-6025 2150);
WIRE 16 -1 (-6025 2150)(-6025 2100);
WIRE 16 -1 (-5075 2100)(-6025 2100);
WIRE 16 -1 (-6025 2100)(-6025 2050);
WIRE 16 -1 (-5075 2050)(-6025 2050);
WIRE 16 -1 (-6025 2050)(-6025 2000);
WIRE 16 -1 (-5075 2000)(-6025 2000);
WIRE 16 -1 (-6025 2000)(-6025 1950);
WIRE 16 -1 (-5075 1950)(-6025 1950);
WIRE 16 -1 (-6025 1950)(-6025 1900);
WIRE 16 -1 (-5075 1900)(-6025 1900);
WIRE 16 -1 (-6025 1900)(-6025 1850);
WIRE 16 -1 (-5075 1850)(-6025 1850);
WIRE 16 -1 (-6025 1850)(-6025 1800);
WIRE 16 -1 (-5075 1800)(-6025 1800);
WIRE 16 -1 (-6025 1800)(-6025 1750);
WIRE 16 -1 (-5075 1750)(-6025 1750);
WIRE 16 -1 (-6025 1750)(-6025 1700);
WIRE 16 -1 (-5075 1700)(-6025 1700);
WIRE 16 -1 (-6025 1700)(-6025 1525);
WIRE 16 -1 (-2525 1700)(-3475 1700);
FORCEPROP 0 LAST SIG_NAME TP_CPU1_UPI2_RSVD_CC12
J 0
(-3125 1710);
DISPLAY 0.617021 (-3125 1710);
PAINT ORANGE (-3125 1710);
FORCEPROP 2 LASTPROP $XRERR UNIQUE?
J 0
(-2495 1700);
DISPLAY 0.638298 (-2495 1700);
PAINT MONO (-2495 1700);
DISPLAY INVISIBLE (-2495 1700);
WIRE 16 -1 (-2525 1750)(-3475 1750);
FORCEPROP 0 LAST SIG_NAME TP_CPU1_UPI2_RSVD_CC10
J 0
(-3125 1760);
DISPLAY 0.617021 (-3125 1760);
PAINT ORANGE (-3125 1760);
FORCEPROP 2 LASTPROP $XRERR UNIQUE?
J 0
(-2495 1750);
DISPLAY 0.638298 (-2495 1750);
PAINT MONO (-2495 1750);
DISPLAY INVISIBLE (-2495 1750);
WIRE 16 -1 (-2525 1800)(-3475 1800);
FORCEPROP 0 LAST SIG_NAME TP_CPU1_UPI2_RSVD_CE12
J 0
(-3125 1810);
DISPLAY 0.617021 (-3125 1810);
PAINT ORANGE (-3125 1810);
FORCEPROP 2 LASTPROP $XRERR UNIQUE?
J 0
(-2495 1800);
DISPLAY 0.638298 (-2495 1800);
PAINT MONO (-2495 1800);
DISPLAY INVISIBLE (-2495 1800);
WIRE 16 -1 (-2525 1850)(-3475 1850);
FORCEPROP 0 LAST SIG_NAME TP_CPU1_UPI2_RSVD_CH11
J 0
(-3125 1860);
DISPLAY 0.617021 (-3125 1860);
PAINT ORANGE (-3125 1860);
FORCEPROP 2 LASTPROP $XRERR UNIQUE?
J 0
(-2495 1850);
DISPLAY 0.638298 (-2495 1850);
PAINT MONO (-2495 1850);
DISPLAY INVISIBLE (-2495 1850);
WIRE 16 -1 (-2525 1900)(-3475 1900);
FORCEPROP 0 LAST SIG_NAME TP_CPU1_UPI2_RSVD_CF13
J 0
(-3125 1910);
DISPLAY 0.617021 (-3125 1910);
PAINT ORANGE (-3125 1910);
FORCEPROP 2 LASTPROP $XRERR UNIQUE?
J 0
(-2495 1900);
DISPLAY 0.638298 (-2495 1900);
PAINT MONO (-2495 1900);
DISPLAY INVISIBLE (-2495 1900);
WIRE 16 -1 (-2525 1950)(-3475 1950);
FORCEPROP 0 LAST SIG_NAME TP_CPU1_UPI2_RSVD_CJ14
J 0
(-3125 1960);
DISPLAY 0.617021 (-3125 1960);
PAINT ORANGE (-3125 1960);
FORCEPROP 2 LASTPROP $XRERR UNIQUE?
J 0
(-2495 1950);
DISPLAY 0.638298 (-2495 1950);
PAINT MONO (-2495 1950);
DISPLAY INVISIBLE (-2495 1950);
WIRE 16 -1 (-2525 2000)(-3475 2000);
FORCEPROP 0 LAST SIG_NAME TP_CPU1_UPI2_RSVD_CM13
J 0
(-3125 2010);
DISPLAY 0.617021 (-3125 2010);
PAINT ORANGE (-3125 2010);
FORCEPROP 2 LASTPROP $XRERR UNIQUE?
J 0
(-2495 2000);
DISPLAY 0.638298 (-2495 2000);
PAINT MONO (-2495 2000);
DISPLAY INVISIBLE (-2495 2000);
WIRE 16 -1 (-2525 2750)(-3475 2750);
FORCEPROP 0 LAST SIG_NAME TP_CPU1_UPI2_RSVD_CA12
J 0
(-3125 2760);
DISPLAY 0.617021 (-3125 2760);
PAINT ORANGE (-3125 2760);
FORCEPROP 2 LASTPROP $XRERR UNIQUE?
J 0
(-2495 2750);
DISPLAY 0.638298 (-2495 2750);
PAINT MONO (-2495 2750);
DISPLAY INVISIBLE (-2495 2750);
WIRE 16 -1 (-2525 2800)(-3475 2800);
FORCEPROP 0 LAST SIG_NAME TP_CPU1_UPI2_RSVD_CB11
J 0
(-3125 2810);
DISPLAY 0.617021 (-3125 2810);
PAINT ORANGE (-3125 2810);
FORCEPROP 2 LASTPROP $XRERR UNIQUE?
J 0
(-2495 2800);
DISPLAY 0.638298 (-2495 2800);
PAINT MONO (-2495 2800);
DISPLAY INVISIBLE (-2495 2800);
WIRE 16 -1 (-2525 2850)(-3475 2850);
FORCEPROP 0 LAST SIG_NAME TP_CPU1_UPI2_RSVD_CD11
J 0
(-3125 2860);
DISPLAY 0.617021 (-3125 2860);
PAINT ORANGE (-3125 2860);
FORCEPROP 2 LASTPROP $XRERR UNIQUE?
J 0
(-2495 2850);
DISPLAY 0.638298 (-2495 2850);
PAINT MONO (-2495 2850);
DISPLAY INVISIBLE (-2495 2850);
WIRE 16 -1 (-2525 2900)(-3475 2900);
FORCEPROP 0 LAST SIG_NAME TP_CPU1_UPI2_RSVD_CF11
J 0
(-3125 2910);
DISPLAY 0.617021 (-3125 2910);
PAINT ORANGE (-3125 2910);
FORCEPROP 2 LASTPROP $XRERR UNIQUE?
J 0
(-2495 2900);
DISPLAY 0.638298 (-2495 2900);
PAINT MONO (-2495 2900);
DISPLAY INVISIBLE (-2495 2900);
WIRE 16 -1 (-2525 2950)(-3475 2950);
FORCEPROP 0 LAST SIG_NAME TP_CPU1_UPI2_RSVD_CG12
J 0
(-3125 2960);
DISPLAY 0.617021 (-3125 2960);
PAINT ORANGE (-3125 2960);
FORCEPROP 2 LASTPROP $XRERR UNIQUE?
J 0
(-2495 2950);
DISPLAY 0.638298 (-2495 2950);
PAINT MONO (-2495 2950);
DISPLAY INVISIBLE (-2495 2950);
WIRE 16 -1 (-2525 3000)(-3475 3000);
FORCEPROP 0 LAST SIG_NAME TP_CPU1_UPI2_RSVD_CH13
J 0
(-3125 3010);
DISPLAY 0.617021 (-3125 3010);
PAINT ORANGE (-3125 3010);
FORCEPROP 2 LASTPROP $XRERR UNIQUE?
J 0
(-2495 3000);
DISPLAY 0.638298 (-2495 3000);
PAINT MONO (-2495 3000);
DISPLAY INVISIBLE (-2495 3000);
WIRE 16 -1 (-2525 3050)(-3475 3050);
FORCEPROP 0 LAST SIG_NAME TP_CPU1_UPI2_RSVD_CK13
J 0
(-3125 3060);
DISPLAY 0.617021 (-3125 3060);
PAINT ORANGE (-3125 3060);
FORCEPROP 2 LASTPROP $XRERR UNIQUE?
J 0
(-2495 3050);
DISPLAY 0.638298 (-2495 3050);
PAINT MONO (-2495 3050);
DISPLAY INVISIBLE (-2495 3050);
WIRE 16 -1 (-2525 3100)(-3475 3100);
FORCEPROP 0 LAST SIG_NAME TP_CPU1_UPI2_RSVD_CR14
J 0
(-3125 3110);
DISPLAY 0.617021 (-3125 3110);
PAINT ORANGE (-3125 3110);
FORCEPROP 2 LASTPROP $XRERR UNIQUE?
J 0
(-2495 3100);
DISPLAY 0.638298 (-2495 3100);
PAINT MONO (-2495 3100);
DISPLAY INVISIBLE (-2495 3100);
WIRE 16 -1 (-2525 3150)(-3475 3150);
FORCEPROP 0 LAST SIG_NAME TP_CPU1_UPI2_RSVD_CV13
J 0
(-3125 3160);
DISPLAY 0.617021 (-3125 3160);
PAINT ORANGE (-3125 3160);
FORCEPROP 2 LASTPROP $XRERR UNIQUE?
J 0
(-2495 3150);
DISPLAY 0.638298 (-2495 3150);
PAINT MONO (-2495 3150);
DISPLAY INVISIBLE (-2495 3150);
WIRE 16 -1 (-2525 3200)(-3475 3200);
FORCEPROP 0 LAST SIG_NAME TP_CPU1_UPI2_RSVD_CW16
J 0
(-3125 3210);
DISPLAY 0.617021 (-3125 3210);
PAINT ORANGE (-3125 3210);
FORCEPROP 2 LASTPROP $XRERR UNIQUE?
J 0
(-2495 3200);
DISPLAY 0.638298 (-2495 3200);
PAINT MONO (-2495 3200);
DISPLAY INVISIBLE (-2495 3200);
WIRE 16 -1 (-2525 3250)(-3475 3250);
FORCEPROP 0 LAST SIG_NAME TP_CPU1_UPI2_RSVD_DB15
J 0
(-3125 3260);
DISPLAY 0.617021 (-3125 3260);
PAINT ORANGE (-3125 3260);
FORCEPROP 2 LASTPROP $XRERR UNIQUE?
J 0
(-2495 3250);
DISPLAY 0.638298 (-2495 3250);
PAINT MONO (-2495 3250);
DISPLAY INVISIBLE (-2495 3250);
WIRE 16 -1 (-2525 3300)(-3475 3300);
FORCEPROP 0 LAST SIG_NAME TP_CPU1_UPI2_RSVD_DD15
J 0
(-3125 3310);
DISPLAY 0.617021 (-3125 3310);
PAINT ORANGE (-3125 3310);
FORCEPROP 2 LASTPROP $XRERR UNIQUE?
J 0
(-2495 3300);
DISPLAY 0.638298 (-2495 3300);
PAINT MONO (-2495 3300);
DISPLAY INVISIBLE (-2495 3300);
WIRE 16 -1 (-2525 3350)(-3475 3350);
FORCEPROP 0 LAST SIG_NAME TP_CPU1_UPI2_RSVD_DE16
J 0
(-3125 3360);
DISPLAY 0.617021 (-3125 3360);
PAINT ORANGE (-3125 3360);
FORCEPROP 2 LASTPROP $XRERR UNIQUE?
J 0
(-2495 3350);
DISPLAY 0.638298 (-2495 3350);
PAINT MONO (-2495 3350);
DISPLAY INVISIBLE (-2495 3350);
WIRE 16 -1 (-2525 3400)(-3475 3400);
FORCEPROP 0 LAST SIG_NAME TP_CPU1_UPI2_RSVD_DF17
J 0
(-3125 3410);
DISPLAY 0.617021 (-3125 3410);
PAINT ORANGE (-3125 3410);
FORCEPROP 2 LASTPROP $XRERR UNIQUE?
J 0
(-2495 3400);
DISPLAY 0.638298 (-2495 3400);
PAINT MONO (-2495 3400);
DISPLAY INVISIBLE (-2495 3400);
WIRE 16 -1 (-2525 3450)(-3475 3450);
FORCEPROP 0 LAST SIG_NAME TP_CPU1_UPI2_RSVD_DH17
J 0
(-3125 3460);
DISPLAY 0.617021 (-3125 3460);
PAINT ORANGE (-3125 3460);
FORCEPROP 2 LASTPROP $XRERR UNIQUE?
J 0
(-2495 3450);
DISPLAY 0.638298 (-2495 3450);
PAINT MONO (-2495 3450);
DISPLAY INVISIBLE (-2495 3450);
WIRE 16 -1 (-2525 3500)(-3475 3500);
FORCEPROP 0 LAST SIG_NAME TP_CPU1_UPI2_RSVD_DJ18
J 0
(-3125 3510);
DISPLAY 0.617021 (-3125 3510);
PAINT ORANGE (-3125 3510);
FORCEPROP 2 LASTPROP $XRERR UNIQUE?
J 0
(-2495 3500);
DISPLAY 0.638298 (-2495 3500);
PAINT MONO (-2495 3500);
DISPLAY INVISIBLE (-2495 3500);
WIRE 16 -1 (-2525 3550)(-3475 3550);
FORCEPROP 0 LAST SIG_NAME TP_CPU1_UPI2_RSVD_DJ20
J 0
(-3125 3560);
DISPLAY 0.617021 (-3125 3560);
PAINT ORANGE (-3125 3560);
FORCEPROP 2 LASTPROP $XRERR UNIQUE?
J 0
(-2495 3550);
DISPLAY 0.638298 (-2495 3550);
PAINT MONO (-2495 3550);
DISPLAY INVISIBLE (-2495 3550);
WIRE 16 -1 (-2525 3600)(-3475 3600);
FORCEPROP 0 LAST SIG_NAME TP_CPU1_UPI2_RSVD_DK19
J 0
(-3125 3610);
DISPLAY 0.617021 (-3125 3610);
PAINT ORANGE (-3125 3610);
FORCEPROP 2 LASTPROP $XRERR UNIQUE?
J 0
(-2495 3600);
DISPLAY 0.638298 (-2495 3600);
PAINT MONO (-2495 3600);
DISPLAY INVISIBLE (-2495 3600);
WIRE 16 -1 (-2525 3650)(-3475 3650);
FORCEPROP 0 LAST SIG_NAME TP_CPU1_UPI2_RSVD_DN20
J 0
(-3125 3660);
DISPLAY 0.617021 (-3125 3660);
PAINT ORANGE (-3125 3660);
FORCEPROP 2 LASTPROP $XRERR UNIQUE?
J 0
(-2495 3650);
DISPLAY 0.638298 (-2495 3650);
PAINT MONO (-2495 3650);
DISPLAY INVISIBLE (-2495 3650);
WIRE 16 -1 (-2525 3700)(-3475 3700);
FORCEPROP 0 LAST SIG_NAME TP_CPU1_UPI2_RSVD_DP21
J 0
(-3125 3710);
DISPLAY 0.617021 (-3125 3710);
PAINT ORANGE (-3125 3710);
FORCEPROP 2 LASTPROP $XRERR UNIQUE?
J 0
(-2495 3700);
DISPLAY 0.638298 (-2495 3700);
PAINT MONO (-2495 3700);
DISPLAY INVISIBLE (-2495 3700);
WIRE 16 -1 (-2525 2050)(-3475 2050);
FORCEPROP 0 LAST SIG_NAME TP_CPU1_UPI2_RSVD_CU14
J 0
(-3125 2060);
DISPLAY 0.617021 (-3125 2060);
PAINT ORANGE (-3125 2060);
FORCEPROP 2 LASTPROP $XRERR UNIQUE?
J 0
(-2495 2050);
DISPLAY 0.638298 (-2495 2050);
PAINT MONO (-2495 2050);
DISPLAY INVISIBLE (-2495 2050);
WIRE 16 -1 (-2525 2100)(-3475 2100);
FORCEPROP 0 LAST SIG_NAME TP_CPU1_UPI2_RSVD_CW14
J 0
(-3125 2110);
DISPLAY 0.617021 (-3125 2110);
PAINT ORANGE (-3125 2110);
FORCEPROP 2 LASTPROP $XRERR UNIQUE?
J 0
(-2495 2100);
DISPLAY 0.638298 (-2495 2100);
PAINT MONO (-2495 2100);
DISPLAY INVISIBLE (-2495 2100);
WIRE 16 -1 (-2525 2150)(-3475 2150);
FORCEPROP 0 LAST SIG_NAME TP_CPU1_UPI2_RSVD_DA16
J 0
(-3125 2160);
DISPLAY 0.617021 (-3125 2160);
PAINT ORANGE (-3125 2160);
FORCEPROP 2 LASTPROP $XRERR UNIQUE?
J 0
(-2495 2150);
DISPLAY 0.638298 (-2495 2150);
PAINT MONO (-2495 2150);
DISPLAY INVISIBLE (-2495 2150);
WIRE 16 -1 (-2525 2200)(-3475 2200);
FORCEPROP 0 LAST SIG_NAME TP_CPU1_UPI2_RSVD_DC16
J 0
(-3125 2210);
DISPLAY 0.617021 (-3125 2210);
PAINT ORANGE (-3125 2210);
FORCEPROP 2 LASTPROP $XRERR UNIQUE?
J 0
(-2495 2200);
DISPLAY 0.638298 (-2495 2200);
PAINT MONO (-2495 2200);
DISPLAY INVISIBLE (-2495 2200);
WIRE 16 -1 (-2525 2250)(-3475 2250);
FORCEPROP 0 LAST SIG_NAME TP_CPU1_UPI2_RSVD_DF15
J 0
(-3125 2260);
DISPLAY 0.617021 (-3125 2260);
PAINT ORANGE (-3125 2260);
FORCEPROP 2 LASTPROP $XRERR UNIQUE?
J 0
(-2495 2250);
DISPLAY 0.638298 (-2495 2250);
PAINT MONO (-2495 2250);
DISPLAY INVISIBLE (-2495 2250);
WIRE 16 -1 (-2525 2300)(-3475 2300);
FORCEPROP 0 LAST SIG_NAME TP_CPU1_UPI2_RSVD_DD17
J 0
(-3125 2310);
DISPLAY 0.617021 (-3125 2310);
PAINT ORANGE (-3125 2310);
FORCEPROP 2 LASTPROP $XRERR UNIQUE?
J 0
(-2495 2300);
DISPLAY 0.638298 (-2495 2300);
PAINT MONO (-2495 2300);
DISPLAY INVISIBLE (-2495 2300);
WIRE 16 -1 (-2525 2350)(-3475 2350);
FORCEPROP 0 LAST SIG_NAME TP_CPU1_UPI2_RSVD_DG18
J 0
(-3125 2360);
DISPLAY 0.617021 (-3125 2360);
PAINT ORANGE (-3125 2360);
FORCEPROP 2 LASTPROP $XRERR UNIQUE?
J 0
(-2495 2350);
DISPLAY 0.638298 (-2495 2350);
PAINT MONO (-2495 2350);
DISPLAY INVISIBLE (-2495 2350);
WIRE 16 -1 (-2525 2400)(-3475 2400);
FORCEPROP 0 LAST SIG_NAME TP_CPU1_UPI2_RSVD_DK17
J 0
(-3125 2410);
DISPLAY 0.617021 (-3125 2410);
PAINT ORANGE (-3125 2410);
FORCEPROP 2 LASTPROP $XRERR UNIQUE?
J 0
(-2495 2400);
DISPLAY 0.638298 (-2495 2400);
PAINT MONO (-2495 2400);
DISPLAY INVISIBLE (-2495 2400);
WIRE 16 -1 (-2525 2450)(-3475 2450);
FORCEPROP 0 LAST SIG_NAME TP_CPU1_UPI2_RSVD_DH19
J 0
(-3125 2460);
DISPLAY 0.617021 (-3125 2460);
PAINT ORANGE (-3125 2460);
FORCEPROP 2 LASTPROP $XRERR UNIQUE?
J 0
(-2495 2450);
DISPLAY 0.638298 (-2495 2450);
PAINT MONO (-2495 2450);
DISPLAY INVISIBLE (-2495 2450);
WIRE 16 -1 (-2525 2500)(-3475 2500);
FORCEPROP 0 LAST SIG_NAME TP_CPU1_UPI2_RSVD_DG20
J 0
(-3125 2510);
DISPLAY 0.617021 (-3125 2510);
PAINT ORANGE (-3125 2510);
FORCEPROP 2 LASTPROP $XRERR UNIQUE?
J 0
(-2495 2500);
DISPLAY 0.638298 (-2495 2500);
PAINT MONO (-2495 2500);
DISPLAY INVISIBLE (-2495 2500);
WIRE 16 -1 (-2525 2550)(-3475 2550);
FORCEPROP 0 LAST SIG_NAME TP_CPU1_UPI2_RSVD_DL20
J 0
(-3125 2560);
DISPLAY 0.617021 (-3125 2560);
PAINT ORANGE (-3125 2560);
FORCEPROP 2 LASTPROP $XRERR UNIQUE?
J 0
(-2495 2550);
DISPLAY 0.638298 (-2495 2550);
PAINT MONO (-2495 2550);
DISPLAY INVISIBLE (-2495 2550);
WIRE 16 -1 (-2525 2600)(-3475 2600);
FORCEPROP 0 LAST SIG_NAME TP_CPU1_UPI2_RSVD_DM21
J 0
(-3125 2610);
DISPLAY 0.617021 (-3125 2610);
PAINT ORANGE (-3125 2610);
FORCEPROP 2 LASTPROP $XRERR UNIQUE?
J 0
(-2495 2600);
DISPLAY 0.638298 (-2495 2600);
PAINT MONO (-2495 2600);
DISPLAY INVISIBLE (-2495 2600);
WIRE 16 -1 (-2525 2650)(-3475 2650);
FORCEPROP 0 LAST SIG_NAME TP_CPU1_UPI2_RSVD_DT21
J 0
(-3125 2660);
DISPLAY 0.617021 (-3125 2660);
PAINT ORANGE (-3125 2660);
FORCEPROP 2 LASTPROP $XRERR UNIQUE?
J 0
(-2495 2650);
DISPLAY 0.638298 (-2495 2650);
PAINT MONO (-2495 2650);
DISPLAY INVISIBLE (-2495 2650);
DOT 1 (-6025 3650);
DOT 1 (-6025 3600);
DOT 1 (-6025 3550);
DOT 1 (-6025 3500);
DOT 1 (-6025 3450);
DOT 1 (-6025 3400);
DOT 1 (-6025 3350);
DOT 1 (-6025 3300);
DOT 1 (-6025 3250);
DOT 1 (-6025 3200);
DOT 1 (-6025 3150);
DOT 1 (-6025 3100);
DOT 1 (-6025 3050);
DOT 1 (-6025 3000);
DOT 1 (-6025 2950);
DOT 1 (-6025 2900);
DOT 1 (-6025 2800);
DOT 1 (-6025 2750);
DOT 1 (-6025 2650);
DOT 1 (-6025 2600);
DOT 1 (-6025 2550);
DOT 1 (-6025 2500);
DOT 1 (-6025 2450);
DOT 1 (-6025 2400);
DOT 1 (-6025 2350);
DOT 1 (-6025 2300);
DOT 1 (-6025 2250);
DOT 1 (-6025 2200);
DOT 1 (-6025 2150);
DOT 1 (-6025 2050);
DOT 1 (-6025 2000);
DOT 1 (-6025 1950);
DOT 1 (-6025 1900);
DOT 1 (-6025 1850);
DOT 1 (-6025 1800);
DOT 1 (-6025 1750);
DOT 1 (-6025 1700);
DOT 1 (-6025 2100);
DOT 1 (-6025 2850);
FORCENOTE
ROOM=CPU1
(-7925 325) 0;
DISPLAY LEFT (-7925 325);
DISPLAY 1.723404 (-7925 325);
PAINT PURPLE (-7925 325);
FORCENOTE
BOM_COST=PROC_SOCKET
(-7925 200) 0;
DISPLAY LEFT (-7925 200);
DISPLAY 1.723404 (-7925 200);
PAINT PURPLE (-7925 200);
QUIT
